# S9S_MB_2U (Grand Teton) — schematic netlist excerpt (pin names and nets, part order shuffled) for the footprints in the layout excerpt that follows; sources: Cadence DE-HDL packaged netlist, KiCad conversion of 03242023_DA0F0TMBIJ0_F0T_Motherboard_J_brd_V01_OCP.brd

PC554  Q_CAP  470PF 50V 10% X7R  pkg 0402  page 284 : A = PVCCIN_CPU1_ATSEN ; B = GND
R3284  Q_RES  1K 1% CHIP  pkg 0402LF  page 166 : A = FM_P2E_EQB0 ; B = GND

(kicad_pcb
	(version 20260206)
	(generator "pcbnew")
	(generator_version "10.0")
	(general
		(thickness 1.6)
		(legacy_teardrops no)
	)
	(paper "A4")
	(title_block
		(title "03242023_DA0F0TMBIJ0_F0T_Motherboard_J_brd_V01_OCP.brd")
		(comment 1 "Grand Teton / footprints 91-92 of 6105")
	)
	(layers
		(0 "F.Cu" signal "TOP")
		(4 "In1.Cu" signal "GND")
		(6 "In2.Cu" signal "IN1")
		(8 "In3.Cu" signal "GND1")
		(10 "In4.Cu" signal "IN2")
		(12 "In5.Cu" signal "GND2")
		(14 "In6.Cu" signal "IN3")
		(16 "In7.Cu" signal "GND3")
		(18 "In8.Cu" signal "VCC")
		(20 "In9.Cu" signal "VCC1")
		(22 "In10.Cu" signal "GND4")
		(24 "In11.Cu" signal "IN4")
		(26 "In12.Cu" signal "GND5")
		(28 "In13.Cu" signal "IN5")
		(30 "In14.Cu" signal "GND6")
		(32 "In15.Cu" signal "IN6")
		(34 "In16.Cu" signal "GND7")
		(2 "B.Cu" signal "BOTTOM")
		(9 "F.Adhes" user "F.Adhesive")
		(11 "B.Adhes" user "B.Adhesive")
		(13 "F.Paste" user "Package Geometry/Pastemask Top")
		(15 "B.Paste" user "Package Geometry/Pastemask Bottom")
		(5 "F.SilkS" user "Ref Des/Silkscreen Top")
		(7 "B.SilkS" user "Ref Des/Silkscreen Bottom")
		(1 "F.Mask" user "Board Geometry/Soldermask Top")
		(3 "B.Mask" user "Board Geometry/Soldermask Bottom")
		(17 "Dwgs.User" user "User.Drawings")
		(19 "Cmts.User" user "User.Comments")
		(21 "Eco1.User" user "User.Eco1")
		(23 "Eco2.User" user "User.Eco2")
		(25 "Edge.Cuts" user "Board Geometry/Outline")
		(27 "Margin" user)
		(31 "F.CrtYd" user "Package Geometry/Place Bound Top")
		(29 "B.CrtYd" user "Package Geometry/Place Bound Bottom")
		(35 "F.Fab" user "Ref Des/Assembly Top")
		(33 "B.Fab" user "Ref Des/Assembly Bottom")
	)
	(footprint ""
		(layer "F.Cu")
		(at 23.431754 -399.532094 90)
		(property "Reference" "R3284"
			(at 0 0 90)
			(layer "F.SilkS")
			(hide yes)
			(effects
				(font
					(size 1.27 1.27)
				)
			)
		)
		(property "Value" ""
			(at 0 0 90)
			(layer "F.Fab")
			(effects
				(font
					(size 1.27 1.27)
				)
			)
		)
		(duplicate_pad_numbers_are_jumpers no)
		(fp_line
			(start 0.7874 -0.4064)
			(end 0.7874 0.4064)
			(stroke
				(width 0.1524)
				(type default)
			)
			(layer "F.SilkS")
		)
		(fp_line
			(start -0.7874 -0.4064)
			(end 0.7874 -0.4064)
			(stroke
				(width 0.1524)
				(type default)
			)
			(layer "F.SilkS")
		)
		(fp_line
			(start 0.7874 0.4064)
			(end -0.7874 0.4064)
			(stroke
				(width 0.1524)
				(type default)
			)
			(layer "F.SilkS")
		)
		(fp_line
			(start -0.7874 0.4064)
			(end -0.7874 -0.4064)
			(stroke
				(width 0.1524)
				(type default)
			)
			(layer "F.SilkS")
		)
		(fp_line
			(start -0.12065 -0.305054)
			(end -0.12065 -0.2794)
			(stroke
				(width 0.1)
				(type default)
			)
			(layer "F.Fab")
		)
		(fp_line
			(start -0.67945 -0.305054)
			(end -0.12065 -0.305054)
			(stroke
				(width 0.1)
				(type default)
			)
			(layer "F.Fab")
		)
		(fp_line
			(start 0.67945 -0.3048)
			(end 0.67945 0.3048)
			(stroke
				(width 0.1)
				(type default)
			)
			(layer "F.Fab")
		)
		(fp_line
			(start 0.12065 -0.3048)
			(end 0.67945 -0.3048)
			(stroke
				(width 0.1)
				(type default)
			)
			(layer "F.Fab")
		)
		(fp_line
			(start 0.12065 -0.2794)
			(end 0.12065 -0.3048)
			(stroke
				(width 0.1)
				(type default)
			)
			(layer "F.Fab")
		)
		(fp_line
			(start -0.12065 -0.2794)
			(end 0.12065 -0.2794)
			(stroke
				(width 0.1)
				(type default)
			)
			(layer "F.Fab")
		)
		(fp_line
			(start 0.120396 0.2794)
			(end -0.12065 0.2794)
			(stroke
				(width 0.1)
				(type default)
			)
			(layer "F.Fab")
		)
		(fp_line
			(start -0.12065 0.2794)
			(end -0.12065 0.3048)
			(stroke
				(width 0.1)
				(type default)
			)
			(layer "F.Fab")
		)
		(fp_line
			(start 0.67945 0.3048)
			(end 0.120396 0.3048)
			(stroke
				(width 0.1)
				(type default)
			)
			(layer "F.Fab")
		)
		(fp_line
			(start 0.120396 0.3048)
			(end 0.120396 0.2794)
			(stroke
				(width 0.1)
				(type default)
			)
			(layer "F.Fab")
		)
		(fp_line
			(start -0.12065 0.3048)
			(end -0.67945 0.3048)
			(stroke
				(width 0.1)
				(type default)
			)
			(layer "F.Fab")
		)
		(fp_line
			(start -0.67945 0.3048)
			(end -0.67945 -0.305054)
			(stroke
				(width 0.1)
				(type default)
			)
			(layer "F.Fab")
		)
		(pad "1" smd circle
			(at -0.40005 0 90)
			(size 0 0)
			(layers "F.Cu" "F.Mask" "F.Paste")
			(net "FM_P2E_EQB0")
		)
		(pad "2" smd circle
			(at 0.40005 0 90)
			(size 0 0)
			(layers "F.Cu" "F.Mask" "F.Paste")
			(net "GND")
		)
	)
	(footprint ""
		(layer "F.Cu")
		(at 114.706654 -357.91775)
		(property "Reference" "PC554"
			(at 0 0 0)
			(layer "F.SilkS")
			(hide yes)
			(effects
				(font
					(size 1.27 1.27)
				)
			)
		)
		(property "Value" ""
			(at 0 0 0)
			(layer "F.Fab")
			(effects
				(font
					(size 1.27 1.27)
				)
			)
		)
		(duplicate_pad_numbers_are_jumpers no)
		(fp_line
			(start -0.7874 -0.4064)
			(end 0.7874 -0.4064)
			(stroke
				(width 0.1524)
				(type default)
			)
			(layer "F.SilkS")
		)
		(fp_line
			(start -0.7874 0.4064)
			(end -0.7874 -0.4064)
			(stroke
				(width 0.1524)
				(type default)
			)
			(layer "F.SilkS")
		)
		(fp_line
			(start 0.7874 -0.4064)
			(end 0.7874 0.4064)
			(stroke
				(width 0.1524)
				(type default)
			)
			(layer "F.SilkS")
		)
		(fp_line
			(start 0.7874 0.4064)
			(end -0.7874 0.4064)
			(stroke
				(width 0.1524)
				(type default)
			)
			(layer "F.SilkS")
		)
		(fp_line
			(start -0.67945 -0.305054)
			(end -0.12065 -0.305054)
			(stroke
				(width 0.1)
				(type default)
			)
			(layer "F.Fab")
		)
		(fp_line
			(start -0.67945 0.3048)
			(end -0.67945 -0.305054)
			(stroke
				(width 0.1)
				(type default)
			)
			(layer "F.Fab")
		)
		(fp_line
			(start -0.12065 -0.305054)
			(end -0.12065 -0.2794)
			(stroke
				(width 0.1)
				(type default)
			)
			(layer "F.Fab")
		)
		(fp_line
			(start -0.12065 -0.2794)
			(end 0.12065 -0.2794)
			(stroke
				(width 0.1)
				(type default)
			)
			(layer "F.Fab")
		)
		(fp_line
			(start -0.12065 0.2794)
			(end -0.12065 0.3048)
			(stroke
				(width 0.1)
				(type default)
			)
			(layer "F.Fab")
		)
		(fp_line
			(start -0.12065 0.3048)
			(end -0.67945 0.3048)
			(stroke
				(width 0.1)
				(type default)
			)
			(layer "F.Fab")
		)
		(fp_line
			(start 0.120396 0.2794)
			(end -0.12065 0.2794)
			(stroke
				(width 0.1)
				(type default)
			)
			(layer "F.Fab")
		)
		(fp_line
			(start 0.120396 0.3048)
			(end 0.120396 0.2794)
			(stroke
				(width 0.1)
				(type default)
			)
			(layer "F.Fab")
		)
		(fp_line
			(start 0.12065 -0.3048)
			(end 0.67945 -0.3048)
			(stroke
				(width 0.1)
				(type default)
			)
			(layer "F.Fab")
		)
		(fp_line
			(start 0.12065 -0.2794)
			(end 0.12065 -0.3048)
			(stroke
				(width 0.1)
				(type default)
			)
			(layer "F.Fab")
		)
		(fp_line
			(start 0.67945 -0.3048)
			(end 0.67945 0.3048)
			(stroke
				(width 0.1)
				(type default)
			)
			(layer "F.Fab")
		)
		(fp_line
			(start 0.67945 0.3048)
			(end 0.120396 0.3048)
			(stroke
				(width 0.1)
				(type default)
			)
			(layer "F.Fab")
		)
		(pad "1" smd circle
			(at -0.40005 0)
			(size 0 0)
			(layers "F.Cu" "F.Mask" "F.Paste")
			(net "PVCCIN_CPU1_ATSEN")
		)
		(pad "2" smd circle
			(at 0.40005 0)
			(size 0 0)
			(layers "F.Cu" "F.Mask" "F.Paste")
			(net "GND")
		)
	)
)
